(kicad_pcb
	(version 20260206)
	(generator "pcbnew")
	(generator_version "10.0")
	(general
		(thickness 1.6)
		(legacy_teardrops no)
	)
	(paper "A4")
	(title_block
		(title "04192023_DAF0TMB3IC0_F0TG_MB_C_brd_V02_OCP.brd")
		(comment 1 "Grand Teton / footprints 6691-6697 of 8354")
	)
	(layers
		(0 "F.Cu" signal "TOP")
		(4 "In1.Cu" signal "GND")
		(6 "In2.Cu" signal "IN1")
		(8 "In3.Cu" signal "GND1")
		(10 "In4.Cu" signal "IN2")
		(12 "In5.Cu" signal "GND2")
		(14 "In6.Cu" signal "IN3")
		(16 "In7.Cu" signal "GND3")
		(18 "In8.Cu" signal "VCC")
		(20 "In9.Cu" signal "VCC1")
		(22 "In10.Cu" signal "GND4")
		(24 "In11.Cu" signal "IN4")
		(26 "In12.Cu" signal "GND5")
		(28 "In13.Cu" signal "IN5")
		(30 "In14.Cu" signal "GND6")
		(32 "In15.Cu" signal "IN6")
		(34 "In16.Cu" signal "GND7")
		(2 "B.Cu" signal "BOTTOM")
		(9 "F.Adhes" user "F.Adhesive")
		(11 "B.Adhes" user "B.Adhesive")
		(13 "F.Paste" user "Package Geometry/Pastemask Top")
		(15 "B.Paste" user "Package Geometry/Pastemask Bottom")
		(5 "F.SilkS" user "Ref Des/Silkscreen Top")
		(7 "B.SilkS" user "Ref Des/Silkscreen Bottom")
		(1 "F.Mask" user "Board Geometry/Soldermask Top")
		(3 "B.Mask" user "Board Geometry/Soldermask Bottom")
		(17 "Dwgs.User" user "User.Drawings")
		(19 "Cmts.User" user "User.Comments")
		(21 "Eco1.User" user "User.Eco1")
		(23 "Eco2.User" user "User.Eco2")
		(25 "Edge.Cuts" user "Board Geometry/Outline")
		(27 "Margin" user)
		(31 "F.CrtYd" user "Package Geometry/Place Bound Top")
		(29 "B.CrtYd" user "Package Geometry/Place Bound Bottom")
		(35 "F.Fab" user "Ref Des/Assembly Top")
		(33 "B.Fab" user "Ref Des/Assembly Bottom")
	)
	(footprint ""
		(layer "B.Cu")
		(at 129.188972 -41.947592 -90)
		(property "Reference" "C6078"
			(at 0 0 90)
			(layer "B.SilkS")
			(hide yes)
			(effects
				(font
					(size 1.27 1.27)
				)
				(justify mirror)
			)
		)
		(property "Value" ""
			(at 0 0 90)
			(layer "B.Fab")
			(effects
				(font
					(size 1.27 1.27)
				)
				(justify mirror)
			)
		)
		(duplicate_pad_numbers_are_jumpers no)
		(fp_line
			(start -0.7874 0.4064)
			(end 0.7874 0.4064)
			(stroke
				(width 0.1524)
				(type default)
			)
			(layer "B.SilkS")
		)
		(fp_line
			(start 0.7874 0.4064)
			(end 0.7874 -0.4064)
			(stroke
				(width 0.1524)
				(type default)
			)
			(layer "B.SilkS")
		)
		(fp_line
			(start -0.7874 -0.4064)
			(end -0.7874 0.4064)
			(stroke
				(width 0.1524)
				(type default)
			)
			(layer "B.SilkS")
		)
		(fp_line
			(start 0.7874 -0.4064)
			(end -0.7874 -0.4064)
			(stroke
				(width 0.1524)
				(type default)
			)
			(layer "B.SilkS")
		)
		(fp_line
			(start -0.67945 0.3048)
			(end -0.120396 0.3048)
			(stroke
				(width 0.1)
				(type default)
			)
			(layer "B.Fab")
		)
		(fp_line
			(start -0.120396 0.3048)
			(end -0.120396 0.2794)
			(stroke
				(width 0.1)
				(type default)
			)
			(layer "B.Fab")
		)
		(fp_line
			(start 0.12065 0.3048)
			(end 0.67945 0.3048)
			(stroke
				(width 0.1)
				(type default)
			)
			(layer "B.Fab")
		)
		(fp_line
			(start 0.67945 0.3048)
			(end 0.67945 -0.305054)
			(stroke
				(width 0.1)
				(type default)
			)
			(layer "B.Fab")
		)
		(fp_line
			(start -0.120396 0.2794)
			(end 0.12065 0.2794)
			(stroke
				(width 0.1)
				(type default)
			)
			(layer "B.Fab")
		)
		(fp_line
			(start 0.12065 0.2794)
			(end 0.12065 0.3048)
			(stroke
				(width 0.1)
				(type default)
			)
			(layer "B.Fab")
		)
		(fp_line
			(start -0.12065 -0.2794)
			(end -0.12065 -0.3048)
			(stroke
				(width 0.1)
				(type default)
			)
			(layer "B.Fab")
		)
		(fp_line
			(start 0.12065 -0.2794)
			(end -0.12065 -0.2794)
			(stroke
				(width 0.1)
				(type default)
			)
			(layer "B.Fab")
		)
		(fp_line
			(start -0.67945 -0.3048)
			(end -0.67945 0.3048)
			(stroke
				(width 0.1)
				(type default)
			)
			(layer "B.Fab")
		)
		(fp_line
			(start -0.12065 -0.3048)
			(end -0.67945 -0.3048)
			(stroke
				(width 0.1)
				(type default)
			)
			(layer "B.Fab")
		)
		(fp_line
			(start 0.12065 -0.305054)
			(end 0.12065 -0.2794)
			(stroke
				(width 0.1)
				(type default)
			)
			(layer "B.Fab")
		)
		(fp_line
			(start 0.67945 -0.305054)
			(end 0.12065 -0.305054)
			(stroke
				(width 0.1)
				(type default)
			)
			(layer "B.Fab")
		)
		(pad "1" smd circle
			(at 0.40005 0 90)
			(size 0 0)
			(layers "B.Cu" "B.Mask" "B.Paste")
			(net "P1V2_AUX")
		)
		(pad "2" smd circle
			(at -0.40005 0 90)
			(size 0 0)
			(layers "B.Cu" "B.Mask" "B.Paste")
			(net "GND")
		)
	)
	(footprint ""
		(layer "B.Cu")
		(at 191.26454 -400.709892 90)
		(property "Reference" "R3936"
			(at 0 0 90)
			(layer "B.SilkS")
			(hide yes)
			(effects
				(font
					(size 1.27 1.27)
				)
				(justify mirror)
			)
		)
		(property "Value" ""
			(at 0 0 90)
			(layer "B.Fab")
			(effects
				(font
					(size 1.27 1.27)
				)
				(justify mirror)
			)
		)
		(duplicate_pad_numbers_are_jumpers no)
		(fp_line
			(start 0.7874 -0.4064)
			(end -0.7874 -0.4064)
			(stroke
				(width 0.1524)
				(type default)
			)
			(layer "B.SilkS")
		)
		(fp_line
			(start -0.7874 -0.4064)
			(end -0.7874 0.4064)
			(stroke
				(width 0.1524)
				(type default)
			)
			(layer "B.SilkS")
		)
		(fp_line
			(start 0.7874 0.4064)
			(end 0.7874 -0.4064)
			(stroke
				(width 0.1524)
				(type default)
			)
			(layer "B.SilkS")
		)
		(fp_line
			(start -0.7874 0.4064)
			(end 0.7874 0.4064)
			(stroke
				(width 0.1524)
				(type default)
			)
			(layer "B.SilkS")
		)
		(fp_line
			(start 0.67945 -0.305054)
			(end 0.12065 -0.305054)
			(stroke
				(width 0.1)
				(type default)
			)
			(layer "B.Fab")
		)
		(fp_line
			(start 0.12065 -0.305054)
			(end 0.12065 -0.2794)
			(stroke
				(width 0.1)
				(type default)
			)
			(layer "B.Fab")
		)
		(fp_line
			(start -0.12065 -0.3048)
			(end -0.67945 -0.3048)
			(stroke
				(width 0.1)
				(type default)
			)
			(layer "B.Fab")
		)
		(fp_line
			(start -0.67945 -0.3048)
			(end -0.67945 0.3048)
			(stroke
				(width 0.1)
				(type default)
			)
			(layer "B.Fab")
		)
		(fp_line
			(start 0.12065 -0.2794)
			(end -0.12065 -0.2794)
			(stroke
				(width 0.1)
				(type default)
			)
			(layer "B.Fab")
		)
		(fp_line
			(start -0.12065 -0.2794)
			(end -0.12065 -0.3048)
			(stroke
				(width 0.1)
				(type default)
			)
			(layer "B.Fab")
		)
		(fp_line
			(start 0.12065 0.2794)
			(end 0.12065 0.3048)
			(stroke
				(width 0.1)
				(type default)
			)
			(layer "B.Fab")
		)
		(fp_line
			(start -0.120396 0.2794)
			(end 0.12065 0.2794)
			(stroke
				(width 0.1)
				(type default)
			)
			(layer "B.Fab")
		)
		(fp_line
			(start 0.67945 0.3048)
			(end 0.67945 -0.305054)
			(stroke
				(width 0.1)
				(type default)
			)
			(layer "B.Fab")
		)
		(fp_line
			(start 0.12065 0.3048)
			(end 0.67945 0.3048)
			(stroke
				(width 0.1)
				(type default)
			)
			(layer "B.Fab")
		)
		(fp_line
			(start -0.120396 0.3048)
			(end -0.120396 0.2794)
			(stroke
				(width 0.1)
				(type default)
			)
			(layer "B.Fab")
		)
		(fp_line
			(start -0.67945 0.3048)
			(end -0.120396 0.3048)
			(stroke
				(width 0.1)
				(type default)
			)
			(layer "B.Fab")
		)
		(pad "1" smd circle
			(at 0.40005 0 270)
			(size 0 0)
			(layers "B.Cu" "B.Mask" "B.Paste")
			(net "HSC_VDD")
		)
		(pad "2" smd circle
			(at -0.40005 0 270)
			(size 0 0)
			(layers "B.Cu" "B.Mask" "B.Paste")
			(net "HSC_D_OC")
		)
	)
	(footprint ""
		(layer "B.Cu")
		(at 307.500528 -338.082128 -90)
		(property "Reference" "PC128_4"
			(at 0 0 90)
			(layer "B.SilkS")
			(hide yes)
			(effects
				(font
					(size 1.27 1.27)
				)
				(justify mirror)
			)
		)
		(property "Value" ""
			(at 0 0 90)
			(layer "B.Fab")
			(effects
				(font
					(size 1.27 1.27)
				)
				(justify mirror)
			)
		)
		(duplicate_pad_numbers_are_jumpers no)
		(fp_line
			(start -1.524 0.762)
			(end 1.524 0.762)
			(stroke
				(width 0.1524)
				(type default)
			)
			(layer "B.SilkS")
		)
		(fp_line
			(start 1.524 0.762)
			(end 1.524 -0.762)
			(stroke
				(width 0.1524)
				(type default)
			)
			(layer "B.SilkS")
		)
		(fp_line
			(start -1.524 -0.762)
			(end -1.524 0.762)
			(stroke
				(width 0.1524)
				(type default)
			)
			(layer "B.SilkS")
		)
		(fp_line
			(start 1.524 -0.762)
			(end -1.524 -0.762)
			(stroke
				(width 0.1524)
				(type default)
			)
			(layer "B.SilkS")
		)
		(fp_line
			(start -1.1049 0.724916)
			(end -1.1049 -0.724916)
			(stroke
				(width 0.1)
				(type default)
			)
			(layer "B.Fab")
		)
		(fp_line
			(start 1.1049 0.724916)
			(end -1.1049 0.724916)
			(stroke
				(width 0.1)
				(type default)
			)
			(layer "B.Fab")
		)
		(fp_line
			(start -1.1049 -0.724916)
			(end 1.1049 -0.724916)
			(stroke
				(width 0.1)
				(type default)
			)
			(layer "B.Fab")
		)
		(fp_line
			(start 1.1049 -0.724916)
			(end 1.1049 0.724916)
			(stroke
				(width 0.1)
				(type default)
			)
			(layer "B.Fab")
		)
		(pad "1" smd rect
			(at 0.889 0 270)
			(size 1.016 1.27)
			(layers "B.Cu" "B.Mask" "B.Paste")
			(net "PVDDCR_CPU1_P0")
		)
		(pad "2" smd rect
			(at -0.889 0 270)
			(size 1.016 1.27)
			(layers "B.Cu" "B.Mask" "B.Paste")
			(net "GND")
		)
	)
	(footprint ""
		(layer "B.Cu")
		(at 322.878958 -195.662296)
		(property "Reference" "R411"
			(at 0 0 0)
			(layer "B.SilkS")
			(hide yes)
			(effects
				(font
					(size 1.27 1.27)
				)
				(justify mirror)
			)
		)
		(property "Value" ""
			(at 0 0 0)
			(layer "B.Fab")
			(effects
				(font
					(size 1.27 1.27)
				)
				(justify mirror)
			)
		)
		(duplicate_pad_numbers_are_jumpers no)
		(fp_line
			(start -0.7874 -0.4064)
			(end -0.7874 0.4064)
			(stroke
				(width 0.1524)
				(type default)
			)
			(layer "B.SilkS")
		)
		(fp_line
			(start -0.7874 0.4064)
			(end 0.7874 0.4064)
			(stroke
				(width 0.1524)
				(type default)
			)
			(layer "B.SilkS")
		)
		(fp_line
			(start 0.7874 -0.4064)
			(end -0.7874 -0.4064)
			(stroke
				(width 0.1524)
				(type default)
			)
			(layer "B.SilkS")
		)
		(fp_line
			(start 0.7874 0.4064)
			(end 0.7874 -0.4064)
			(stroke
				(width 0.1524)
				(type default)
			)
			(layer "B.SilkS")
		)
		(fp_line
			(start -0.67945 -0.3048)
			(end -0.67945 0.3048)
			(stroke
				(width 0.1)
				(type default)
			)
			(layer "B.Fab")
		)
		(fp_line
			(start -0.67945 0.3048)
			(end -0.120396 0.3048)
			(stroke
				(width 0.1)
				(type default)
			)
			(layer "B.Fab")
		)
		(fp_line
			(start -0.12065 -0.3048)
			(end -0.67945 -0.3048)
			(stroke
				(width 0.1)
				(type default)
			)
			(layer "B.Fab")
		)
		(fp_line
			(start -0.12065 -0.2794)
			(end -0.12065 -0.3048)
			(stroke
				(width 0.1)
				(type default)
			)
			(layer "B.Fab")
		)
		(fp_line
			(start -0.120396 0.2794)
			(end 0.12065 0.2794)
			(stroke
				(width 0.1)
				(type default)
			)
			(layer "B.Fab")
		)
		(fp_line
			(start -0.120396 0.3048)
			(end -0.120396 0.2794)
			(stroke
				(width 0.1)
				(type default)
			)
			(layer "B.Fab")
		)
		(fp_line
			(start 0.12065 -0.305054)
			(end 0.12065 -0.2794)
			(stroke
				(width 0.1)
				(type default)
			)
			(layer "B.Fab")
		)
		(fp_line
			(start 0.12065 -0.2794)
			(end -0.12065 -0.2794)
			(stroke
				(width 0.1)
				(type default)
			)
			(layer "B.Fab")
		)
		(fp_line
			(start 0.12065 0.2794)
			(end 0.12065 0.3048)
			(stroke
				(width 0.1)
				(type default)
			)
			(layer "B.Fab")
		)
		(fp_line
			(start 0.12065 0.3048)
			(end 0.67945 0.3048)
			(stroke
				(width 0.1)
				(type default)
			)
			(layer "B.Fab")
		)
		(fp_line
			(start 0.67945 -0.305054)
			(end 0.12065 -0.305054)
			(stroke
				(width 0.1)
				(type default)
			)
			(layer "B.Fab")
		)
		(fp_line
			(start 0.67945 0.3048)
			(end 0.67945 -0.305054)
			(stroke
				(width 0.1)
				(type default)
			)
			(layer "B.Fab")
		)
		(pad "1" smd circle
			(at 0.40005 0 180)
			(size 0 0)
			(layers "B.Cu" "B.Mask" "B.Paste")
			(net "CPU0_BP3")
		)
		(pad "2" smd circle
			(at -0.40005 0 180)
			(size 0 0)
			(layers "B.Cu" "B.Mask" "B.Paste")
			(net "PVDD18_S5_P0")
		)
	)
	(footprint ""
		(layer "B.Cu")
		(at 161.276284 -193.707512 -90)
		(property "Reference" "R991"
			(at 0 0 90)
			(layer "B.SilkS")
			(hide yes)
			(effects
				(font
					(size 1.27 1.27)
				)
				(justify mirror)
			)
		)
		(property "Value" ""
			(at 0 0 90)
			(layer "B.Fab")
			(effects
				(font
					(size 1.27 1.27)
				)
				(justify mirror)
			)
		)
		(duplicate_pad_numbers_are_jumpers no)
		(fp_line
			(start -0.7874 0.4064)
			(end 0.7874 0.4064)
			(stroke
				(width 0.1524)
				(type default)
			)
			(layer "B.SilkS")
		)
		(fp_line
			(start 0.7874 0.4064)
			(end 0.7874 -0.4064)
			(stroke
				(width 0.1524)
				(type default)
			)
			(layer "B.SilkS")
		)
		(fp_line
			(start -0.7874 -0.4064)
			(end -0.7874 0.4064)
			(stroke
				(width 0.1524)
				(type default)
			)
			(layer "B.SilkS")
		)
		(fp_line
			(start 0.7874 -0.4064)
			(end -0.7874 -0.4064)
			(stroke
				(width 0.1524)
				(type default)
			)
			(layer "B.SilkS")
		)
		(fp_line
			(start -0.67945 0.3048)
			(end -0.120396 0.3048)
			(stroke
				(width 0.1)
				(type default)
			)
			(layer "B.Fab")
		)
		(fp_line
			(start -0.120396 0.3048)
			(end -0.120396 0.2794)
			(stroke
				(width 0.1)
				(type default)
			)
			(layer "B.Fab")
		)
		(fp_line
			(start 0.12065 0.3048)
			(end 0.67945 0.3048)
			(stroke
				(width 0.1)
				(type default)
			)
			(layer "B.Fab")
		)
		(fp_line
			(start 0.67945 0.3048)
			(end 0.67945 -0.305054)
			(stroke
				(width 0.1)
				(type default)
			)
			(layer "B.Fab")
		)
		(fp_line
			(start -0.120396 0.2794)
			(end 0.12065 0.2794)
			(stroke
				(width 0.1)
				(type default)
			)
			(layer "B.Fab")
		)
		(fp_line
			(start 0.12065 0.2794)
			(end 0.12065 0.3048)
			(stroke
				(width 0.1)
				(type default)
			)
			(layer "B.Fab")
		)
		(fp_line
			(start -0.12065 -0.2794)
			(end -0.12065 -0.3048)
			(stroke
				(width 0.1)
				(type default)
			)
			(layer "B.Fab")
		)
		(fp_line
			(start 0.12065 -0.2794)
			(end -0.12065 -0.2794)
			(stroke
				(width 0.1)
				(type default)
			)
			(layer "B.Fab")
		)
		(fp_line
			(start -0.67945 -0.3048)
			(end -0.67945 0.3048)
			(stroke
				(width 0.1)
				(type default)
			)
			(layer "B.Fab")
		)
		(fp_line
			(start -0.12065 -0.3048)
			(end -0.67945 -0.3048)
			(stroke
				(width 0.1)
				(type default)
			)
			(layer "B.Fab")
		)
		(fp_line
			(start 0.12065 -0.305054)
			(end 0.12065 -0.2794)
			(stroke
				(width 0.1)
				(type default)
			)
			(layer "B.Fab")
		)
		(fp_line
			(start 0.67945 -0.305054)
			(end 0.12065 -0.305054)
			(stroke
				(width 0.1)
				(type default)
			)
			(layer "B.Fab")
		)
		(pad "1" smd rect
			(at 0.40005 0 270)
			(size 0.4572 0.508)
			(layers "B.Cu" "B.Mask" "B.Paste")
			(net "I3C_1_SPD_DDRGL_CPU1_R_SDA")
		)
		(pad "2" smd rect
			(at -0.40005 0 270)
			(size 0.4572 0.508)
			(layers "B.Cu" "B.Mask" "B.Paste")
			(net "I3C_SPD_DDRGL_CPU1_BYPASS_SDA")
		)
	)
	(footprint ""
		(layer "B.Cu")
		(at 366.598454 -269.30731 180)
		(property "Reference" "C2208"
			(at 0 0 0)
			(layer "B.SilkS")
			(hide yes)
			(effects
				(font
					(size 1.27 1.27)
				)
				(justify mirror)
			)
		)
		(property "Value" ""
			(at 0 0 0)
			(layer "B.Fab")
			(effects
				(font
					(size 1.27 1.27)
				)
				(justify mirror)
			)
		)
		(duplicate_pad_numbers_are_jumpers no)
		(fp_line
			(start 0.7874 0.4064)
			(end 0.7874 -0.4064)
			(stroke
				(width 0.1524)
				(type default)
			)
			(layer "B.SilkS")
		)
		(fp_line
			(start 0.7874 -0.4064)
			(end -0.7874 -0.4064)
			(stroke
				(width 0.1524)
				(type default)
			)
			(layer "B.SilkS")
		)
		(fp_line
			(start -0.7874 0.4064)
			(end 0.7874 0.4064)
			(stroke
				(width 0.1524)
				(type default)
			)
			(layer "B.SilkS")
		)
		(fp_line
			(start -0.7874 -0.4064)
			(end -0.7874 0.4064)
			(stroke
				(width 0.1524)
				(type default)
			)
			(layer "B.SilkS")
		)
		(fp_line
			(start 0.67945 0.3048)
			(end 0.67945 -0.305054)
			(stroke
				(width 0.1)
				(type default)
			)
			(layer "B.Fab")
		)
		(fp_line
			(start 0.67945 -0.305054)
			(end 0.12065 -0.305054)
			(stroke
				(width 0.1)
				(type default)
			)
			(layer "B.Fab")
		)
		(fp_line
			(start 0.12065 0.3048)
			(end 0.67945 0.3048)
			(stroke
				(width 0.1)
				(type default)
			)
			(layer "B.Fab")
		)
		(fp_line
			(start 0.12065 0.2794)
			(end 0.12065 0.3048)
			(stroke
				(width 0.1)
				(type default)
			)
			(layer "B.Fab")
		)
		(fp_line
			(start 0.12065 -0.2794)
			(end -0.12065 -0.2794)
			(stroke
				(width 0.1)
				(type default)
			)
			(layer "B.Fab")
		)
		(fp_line
			(start 0.12065 -0.305054)
			(end 0.12065 -0.2794)
			(stroke
				(width 0.1)
				(type default)
			)
			(layer "B.Fab")
		)
		(fp_line
			(start -0.120396 0.3048)
			(end -0.120396 0.2794)
			(stroke
				(width 0.1)
				(type default)
			)
			(layer "B.Fab")
		)
		(fp_line
			(start -0.120396 0.2794)
			(end 0.12065 0.2794)
			(stroke
				(width 0.1)
				(type default)
			)
			(layer "B.Fab")
		)
		(fp_line
			(start -0.12065 -0.2794)
			(end -0.12065 -0.3048)
			(stroke
				(width 0.1)
				(type default)
			)
			(layer "B.Fab")
		)
		(fp_line
			(start -0.12065 -0.3048)
			(end -0.67945 -0.3048)
			(stroke
				(width 0.1)
				(type default)
			)
			(layer "B.Fab")
		)
		(fp_line
			(start -0.67945 0.3048)
			(end -0.120396 0.3048)
			(stroke
				(width 0.1)
				(type default)
			)
			(layer "B.Fab")
		)
		(fp_line
			(start -0.67945 -0.3048)
			(end -0.67945 0.3048)
			(stroke
				(width 0.1)
				(type default)
			)
			(layer "B.Fab")
		)
		(pad "1" smd circle
			(at 0.40005 0)
			(size 0 0)
			(layers "B.Cu" "B.Mask" "B.Paste")
			(net "PVDDCR_CPU1_P0")
		)
		(pad "2" smd circle
			(at -0.40005 0)
			(size 0 0)
			(layers "B.Cu" "B.Mask" "B.Paste")
			(net "GND")
		)
	)
	(footprint ""
		(layer "B.Cu")
		(at 393.153138 -391.2616 180)
		(property "Reference" "R1125"
			(at 0 0 0)
			(layer "B.SilkS")
			(hide yes)
			(effects
				(font
					(size 1.27 1.27)
				)
				(justify mirror)
			)
		)
		(property "Value" ""
			(at 0 0 0)
			(layer "B.Fab")
			(effects
				(font
					(size 1.27 1.27)
				)
				(justify mirror)
			)
		)
		(duplicate_pad_numbers_are_jumpers no)
		(fp_line
			(start 0.32512 0.175006)
			(end 0.32512 -0.175006)
			(stroke
				(width 0.1)
				(type default)
			)
			(layer "B.Fab")
		)
		(fp_line
			(start 0.32512 -0.175006)
			(end -0.32512 -0.175006)
			(stroke
				(width 0.1)
				(type default)
			)
			(layer "B.Fab")
		)
		(fp_line
			(start -0.32512 0.175006)
			(end 0.32512 0.175006)
			(stroke
				(width 0.1)
				(type default)
			)
			(layer "B.Fab")
		)
		(fp_line
			(start -0.32512 -0.175006)
			(end -0.32512 0.175006)
			(stroke
				(width 0.1)
				(type default)
			)
			(layer "B.Fab")
		)
		(pad "1" smd rect
			(at 0.2667 0)
			(size 0.3048 0.381)
			(layers "B.Cu" "B.Mask" "B.Paste")
			(net "NCF_CPU0_P3_GND")
		)
		(pad "2" smd rect
			(at -0.2667 0 180)
			(size 0.3048 0.381)
			(layers "B.Cu" "B.Mask" "B.Paste")
			(net "GND")
		)
	)
)
